# SCM (Grand Teton) — schematic netlist excerpt (pin names and nets, part order shuffled) for the footprints in the layout excerpt that follows; sources: Cadence DE-HDL packaged netlist, KiCad conversion of 12092022_DA0F0TMDCD0_F0T_Management_Board_D_brd_V3_OCP.brd

R874  Q_RES  0 5% EMPTY  pkg 0402LF  page 54 : A = PWRGD_P1V8_AUX_R3 ; B = PWRGD_P1V8_AUX_R
C253  Q_CAP  0.1UF 25V 10% X7R  pkg 0402  page 22 : A = P3V3_AUX ; B = GND

(kicad_pcb
	(version 20260206)
	(generator "pcbnew")
	(generator_version "10.0")
	(general
		(thickness 1.6)
		(legacy_teardrops no)
	)
	(paper "A4")
	(title_block
		(title "12092022_DA0F0TMDCD0_F0T_Management_Board_D_brd_V3_OCP.brd")
		(comment 1 "Grand Teton / footprints 390-391 of 1440")
	)
	(layers
		(0 "F.Cu" signal "TOP")
		(4 "In1.Cu" signal "GND")
		(6 "In2.Cu" signal "IN1")
		(8 "In3.Cu" signal "GND1")
		(10 "In4.Cu" signal "IN2")
		(12 "In5.Cu" signal "VCC")
		(14 "In6.Cu" signal "VCC1")
		(16 "In7.Cu" signal "IN3")
		(18 "In8.Cu" signal "GND2")
		(20 "In9.Cu" signal "IN4")
		(22 "In10.Cu" signal "GND3")
		(2 "B.Cu" signal "BOTTOM")
		(9 "F.Adhes" user "F.Adhesive")
		(11 "B.Adhes" user "B.Adhesive")
		(13 "F.Paste" user "Package Geometry/Pastemask Top")
		(15 "B.Paste" user "Package Geometry/Pastemask Bottom")
		(5 "F.SilkS" user "Ref Des/Silkscreen Top")
		(7 "B.SilkS" user "Ref Des/Silkscreen Bottom")
		(1 "F.Mask" user "Board Geometry/Soldermask Top")
		(3 "B.Mask" user "Board Geometry/Soldermask Bottom")
		(17 "Dwgs.User" user "User.Drawings")
		(19 "Cmts.User" user "User.Comments")
		(21 "Eco1.User" user "User.Eco1")
		(23 "Eco2.User" user "User.Eco2")
		(25 "Edge.Cuts" user "Board Geometry/Outline")
		(27 "Margin" user)
		(31 "F.CrtYd" user "Package Geometry/Place Bound Top")
		(29 "B.CrtYd" user "Package Geometry/Place Bound Bottom")
		(35 "F.Fab" user "Ref Des/Assembly Top")
		(33 "B.Fab" user "Ref Des/Assembly Bottom")
	)
	(footprint ""
		(layer "F.Cu")
		(at 37.973 -58.674 -90)
		(property "Reference" "R874"
			(at 0 0 270)
			(layer "F.SilkS")
			(hide yes)
			(effects
				(font
					(size 1.27 1.27)
				)
			)
		)
		(property "Value" ""
			(at 0 0 270)
			(layer "F.Fab")
			(effects
				(font
					(size 1.27 1.27)
				)
			)
		)
		(duplicate_pad_numbers_are_jumpers no)
		(fp_line
			(start -0.7874 0.4064)
			(end -0.7874 -0.4064)
			(stroke
				(width 0.1524)
				(type default)
			)
			(layer "F.SilkS")
		)
		(fp_line
			(start 0.7874 0.4064)
			(end -0.7874 0.4064)
			(stroke
				(width 0.1524)
				(type default)
			)
			(layer "F.SilkS")
		)
		(fp_line
			(start -0.7874 -0.4064)
			(end 0.7874 -0.4064)
			(stroke
				(width 0.1524)
				(type default)
			)
			(layer "F.SilkS")
		)
		(fp_line
			(start 0.7874 -0.4064)
			(end 0.7874 0.4064)
			(stroke
				(width 0.1524)
				(type default)
			)
			(layer "F.SilkS")
		)
		(fp_line
			(start -0.67945 0.3048)
			(end -0.67945 -0.305054)
			(stroke
				(width 0.1)
				(type default)
			)
			(layer "F.Fab")
		)
		(fp_line
			(start -0.12065 0.3048)
			(end -0.67945 0.3048)
			(stroke
				(width 0.1)
				(type default)
			)
			(layer "F.Fab")
		)
		(fp_line
			(start 0.120396 0.3048)
			(end 0.120396 0.2794)
			(stroke
				(width 0.1)
				(type default)
			)
			(layer "F.Fab")
		)
		(fp_line
			(start 0.67945 0.3048)
			(end 0.120396 0.3048)
			(stroke
				(width 0.1)
				(type default)
			)
			(layer "F.Fab")
		)
		(fp_line
			(start -0.12065 0.2794)
			(end -0.12065 0.3048)
			(stroke
				(width 0.1)
				(type default)
			)
			(layer "F.Fab")
		)
		(fp_line
			(start 0.120396 0.2794)
			(end -0.12065 0.2794)
			(stroke
				(width 0.1)
				(type default)
			)
			(layer "F.Fab")
		)
		(fp_line
			(start -0.12065 -0.2794)
			(end 0.12065 -0.2794)
			(stroke
				(width 0.1)
				(type default)
			)
			(layer "F.Fab")
		)
		(fp_line
			(start 0.12065 -0.2794)
			(end 0.12065 -0.3048)
			(stroke
				(width 0.1)
				(type default)
			)
			(layer "F.Fab")
		)
		(fp_line
			(start 0.12065 -0.3048)
			(end 0.67945 -0.3048)
			(stroke
				(width 0.1)
				(type default)
			)
			(layer "F.Fab")
		)
		(fp_line
			(start 0.67945 -0.3048)
			(end 0.67945 0.3048)
			(stroke
				(width 0.1)
				(type default)
			)
			(layer "F.Fab")
		)
		(fp_line
			(start -0.67945 -0.305054)
			(end -0.12065 -0.305054)
			(stroke
				(width 0.1)
				(type default)
			)
			(layer "F.Fab")
		)
		(fp_line
			(start -0.12065 -0.305054)
			(end -0.12065 -0.2794)
			(stroke
				(width 0.1)
				(type default)
			)
			(layer "F.Fab")
		)
		(pad "1" smd circle
			(at -0.40005 0 270)
			(size 0 0)
			(layers "F.Cu" "F.Mask" "F.Paste")
			(net "PWRGD_P1V8_AUX_R3")
		)
		(pad "2" smd circle
			(at 0.40005 0 270)
			(size 0 0)
			(layers "F.Cu" "F.Mask" "F.Paste")
			(net "PWRGD_P1V8_AUX_R")
		)
	)
	(footprint ""
		(layer "F.Cu")
		(at 32.766 -44.45 90)
		(property "Reference" "C253"
			(at 0 0 90)
			(layer "F.SilkS")
			(hide yes)
			(effects
				(font
					(size 1.27 1.27)
				)
			)
		)
		(property "Value" ""
			(at 0 0 90)
			(layer "F.Fab")
			(effects
				(font
					(size 1.27 1.27)
				)
			)
		)
		(duplicate_pad_numbers_are_jumpers no)
		(fp_line
			(start 0.7874 -0.4064)
			(end 0.7874 0.4064)
			(stroke
				(width 0.1524)
				(type default)
			)
			(layer "F.SilkS")
		)
		(fp_line
			(start -0.7874 -0.4064)
			(end 0.7874 -0.4064)
			(stroke
				(width 0.1524)
				(type default)
			)
			(layer "F.SilkS")
		)
		(fp_line
			(start 0.7874 0.4064)
			(end -0.7874 0.4064)
			(stroke
				(width 0.1524)
				(type default)
			)
			(layer "F.SilkS")
		)
		(fp_line
			(start -0.7874 0.4064)
			(end -0.7874 -0.4064)
			(stroke
				(width 0.1524)
				(type default)
			)
			(layer "F.SilkS")
		)
		(fp_line
			(start -0.12065 -0.305054)
			(end -0.12065 -0.2794)
			(stroke
				(width 0.1)
				(type default)
			)
			(layer "F.Fab")
		)
		(fp_line
			(start -0.67945 -0.305054)
			(end -0.12065 -0.305054)
			(stroke
				(width 0.1)
				(type default)
			)
			(layer "F.Fab")
		)
		(fp_line
			(start 0.67945 -0.3048)
			(end 0.67945 0.3048)
			(stroke
				(width 0.1)
				(type default)
			)
			(layer "F.Fab")
		)
		(fp_line
			(start 0.12065 -0.3048)
			(end 0.67945 -0.3048)
			(stroke
				(width 0.1)
				(type default)
			)
			(layer "F.Fab")
		)
		(fp_line
			(start 0.12065 -0.2794)
			(end 0.12065 -0.3048)
			(stroke
				(width 0.1)
				(type default)
			)
			(layer "F.Fab")
		)
		(fp_line
			(start -0.12065 -0.2794)
			(end 0.12065 -0.2794)
			(stroke
				(width 0.1)
				(type default)
			)
			(layer "F.Fab")
		)
		(fp_line
			(start 0.120396 0.2794)
			(end -0.12065 0.2794)
			(stroke
				(width 0.1)
				(type default)
			)
			(layer "F.Fab")
		)
		(fp_line
			(start -0.12065 0.2794)
			(end -0.12065 0.3048)
			(stroke
				(width 0.1)
				(type default)
			)
			(layer "F.Fab")
		)
		(fp_line
			(start 0.67945 0.3048)
			(end 0.120396 0.3048)
			(stroke
				(width 0.1)
				(type default)
			)
			(layer "F.Fab")
		)
		(fp_line
			(start 0.120396 0.3048)
			(end 0.120396 0.2794)
			(stroke
				(width 0.1)
				(type default)
			)
			(layer "F.Fab")
		)
		(fp_line
			(start -0.12065 0.3048)
			(end -0.67945 0.3048)
			(stroke
				(width 0.1)
				(type default)
			)
			(layer "F.Fab")
		)
		(fp_line
			(start -0.67945 0.3048)
			(end -0.67945 -0.305054)
			(stroke
				(width 0.1)
				(type default)
			)
			(layer "F.Fab")
		)
		(pad "1" smd circle
			(at -0.40005 0 90)
			(size 0 0)
			(layers "F.Cu" "F.Mask" "F.Paste")
			(net "P3V3_AUX")
		)
		(pad "2" smd circle
			(at 0.40005 0 90)
			(size 0 0)
			(layers "F.Cu" "F.Mask" "F.Paste")
			(net "GND")
		)
	)
)
